(kicad_pcb
	(version 20241229)
	(generator "pcbnew")
	(generator_version "9.0")
	(general
		(thickness 1.61)
		(legacy_teardrops no)
	)
	(paper "A3")
	(title_block
		(title "SO-DIMM DDR5 Tester")
		(date "2025-11-26")
		(rev "1.3.0")
		(comment 9 "footprints 522-527 of 627")
	)
	(layers
		(0 "F.Cu" signal)
		(4 "In1.Cu" power)
		(6 "In2.Cu" mixed)
		(8 "In3.Cu" power)
		(10 "In4.Cu" mixed)
		(12 "In5.Cu" power)
		(14 "In6.Cu" mixed)
		(16 "In7.Cu" power)
		(18 "In8.Cu" power)
		(20 "In9.Cu" mixed)
		(22 "In10.Cu" power)
		(2 "B.Cu" signal)
		(9 "F.Adhes" user "F.Adhesive")
		(11 "B.Adhes" user "B.Adhesive")
		(13 "F.Paste" user)
		(15 "B.Paste" user)
		(5 "F.SilkS" user "F.Silkscreen")
		(7 "B.SilkS" user "B.Silkscreen")
		(1 "F.Mask" user)
		(3 "B.Mask" user)
		(17 "Dwgs.User" user "User.Drawings")
		(19 "Cmts.User" user "User.Comments")
		(21 "Eco1.User" user "User.Eco1")
		(23 "Eco2.User" user "User.Eco2")
		(25 "Edge.Cuts" user)
		(27 "Margin" user)
		(31 "F.CrtYd" user "F.Courtyard")
		(29 "B.CrtYd" user "B.Courtyard")
		(35 "F.Fab" user)
		(33 "B.Fab" user)
	)
	(footprint "antmicro-footprints:TP_SMD_1mm"
		(layer "B.Cu")
		(at 191 168.7 180)
		(property "Reference" "TP64"
			(at -3.3 -0.4 0)
			(layer "B.SilkS")
			(effects
				(font
					(size 0.7 0.7)
					(thickness 0.15)
				)
				(justify left bottom mirror)
			)
		)
		(property "Value" "TP_1mm_SMD"
			(at 0 -1.4 0)
			(layer "B.Fab")
			(effects
				(font
					(size 0.7 0.7)
					(thickness 0.15)
				)
				(justify left bottom mirror)
			)
		)
		(property "MPN" ""
			(at 0 0 0)
			(unlocked yes)
			(layer "B.Fab")
			(hide yes)
			(effects
				(font
					(size 1 1)
					(thickness 0.15)
				)
				(justify mirror)
			)
		)
		(property "Manufacturer" ""
			(at 0 0 0)
			(unlocked yes)
			(layer "B.Fab")
			(hide yes)
			(effects
				(font
					(size 1 1)
					(thickness 0.15)
				)
				(justify mirror)
			)
		)
		(property "Author" "Antmicro"
			(at 0 0 0)
			(unlocked yes)
			(layer "B.Fab")
			(hide yes)
			(effects
				(font
					(size 1 1)
					(thickness 0.15)
				)
				(justify mirror)
			)
		)
		(property "License" "Apache-2.0"
			(at 0 0 0)
			(unlocked yes)
			(layer "B.Fab")
			(hide yes)
			(effects
				(font
					(size 1 1)
					(thickness 0.15)
				)
				(justify mirror)
			)
		)
		(sheetname "/Supply/")
		(sheetfile "supply.kicad_sch")
		(attr exclude_from_pos_files)
		(fp_circle
			(center 0 0)
			(end 0.6 0)
			(stroke
				(width 0.05)
				(type default)
			)
			(fill no)
			(layer "B.CrtYd")
		)
		(fp_text user "Author: Antmicro"
			(at -0.5 -4 0)
			(layer "B.Fab")
			(effects
				(font
					(size 0.7 0.7)
					(thickness 0.15)
				)
				(justify left bottom mirror)
			)
		)
		(fp_text user "License: Apache-2.0"
			(at -0.5 -5.2 0)
			(layer "B.Fab")
			(effects
				(font
					(size 0.7 0.7)
					(thickness 0.15)
				)
				(justify left bottom mirror)
			)
		)
		(fp_text user "${REFERENCE}"
			(at -0.5 -2.8 0)
			(layer "B.Fab")
			(effects
				(font
					(size 0.7 0.7)
					(thickness 0.15)
				)
				(justify left bottom mirror)
			)
		)
		(pad "1" smd circle
			(at 0 0 180)
			(size 1 1)
			(layers "B.Cu" "B.Mask")
			(net 52 "/Supply/3V3_local")
			(pinfunction "1")
			(pintype "passive")
		)
	)
	(footprint "antmicro-footprints:TP_SMD_1mm"
		(layer "B.Cu")
		(at 202.6 174.8 180)
		(property "Reference" "TP63"
			(at 0.6 -0.4 0)
			(layer "B.SilkS")
			(effects
				(font
					(size 0.7 0.7)
					(thickness 0.15)
				)
				(justify left bottom mirror)
			)
		)
		(property "Value" "TP_1mm_SMD"
			(at 0 -1.4 0)
			(layer "B.Fab")
			(effects
				(font
					(size 0.7 0.7)
					(thickness 0.15)
				)
				(justify left bottom mirror)
			)
		)
		(property "MPN" ""
			(at 0 0 0)
			(unlocked yes)
			(layer "B.Fab")
			(hide yes)
			(effects
				(font
					(size 1 1)
					(thickness 0.15)
				)
				(justify mirror)
			)
		)
		(property "Manufacturer" ""
			(at 0 0 0)
			(unlocked yes)
			(layer "B.Fab")
			(hide yes)
			(effects
				(font
					(size 1 1)
					(thickness 0.15)
				)
				(justify mirror)
			)
		)
		(property "Author" "Antmicro"
			(at 0 0 0)
			(unlocked yes)
			(layer "B.Fab")
			(hide yes)
			(effects
				(font
					(size 1 1)
					(thickness 0.15)
				)
				(justify mirror)
			)
		)
		(property "License" "Apache-2.0"
			(at 0 0 0)
			(unlocked yes)
			(layer "B.Fab")
			(hide yes)
			(effects
				(font
					(size 1 1)
					(thickness 0.15)
				)
				(justify mirror)
			)
		)
		(sheetname "/Supply/")
		(sheetfile "supply.kicad_sch")
		(attr exclude_from_pos_files)
		(fp_circle
			(center 0 0)
			(end 0.6 0)
			(stroke
				(width 0.05)
				(type default)
			)
			(fill no)
			(layer "B.CrtYd")
		)
		(fp_text user "Author: Antmicro"
			(at -0.5 -4 0)
			(layer "B.Fab")
			(effects
				(font
					(size 0.7 0.7)
					(thickness 0.15)
				)
				(justify left bottom mirror)
			)
		)
		(fp_text user "${REFERENCE}"
			(at -0.5 -2.8 0)
			(layer "B.Fab")
			(effects
				(font
					(size 0.7 0.7)
					(thickness 0.15)
				)
				(justify left bottom mirror)
			)
		)
		(fp_text user "License: Apache-2.0"
			(at -0.5 -5.2 0)
			(layer "B.Fab")
			(effects
				(font
					(size 0.7 0.7)
					(thickness 0.15)
				)
				(justify left bottom mirror)
			)
		)
		(pad "1" smd circle
			(at 0 0 180)
			(size 1 1)
			(layers "B.Cu" "B.Mask")
			(net 56 "/Supply/1V2_local")
			(pinfunction "1")
			(pintype "passive")
		)
	)
	(footprint "antmicro-footprints:C_0402_1005Metric"
		(layer "B.Cu")
		(at 137.875001 176.3025 180)
		(descr "Capacitor SMD 0402 (1005 Metric), square (rectangular) end terminal, IPC_7351 nominal, (Body size source: IPC-SM-782 page 76, https://www.pcb-3d.com/wordpress/wp-content/uploads/ipc-sm-782a_amendment_1_and_2.pdf)")
		(tags "capacitor 0402")
		(property "Reference" "C86"
			(at 0 1.17 0)
			(layer "B.SilkS")
			(hide yes)
			(effects
				(font
					(size 0.7 0.7)
					(thickness 0.15)
				)
				(justify left bottom mirror)
			)
		)
		(property "Value" "C_100n_0402"
			(at 0 -1.169 0)
			(layer "B.Fab")
			(effects
				(font
					(size 0.7 0.7)
					(thickness 0.15)
				)
				(justify left bottom mirror)
			)
		)
		(property "Datasheet" "https://www.murata.com/products/productdetail?partno=GRM155R61H104KE14%23"
			(at 0 0 180)
			(layer "F.Fab")
			(hide yes)
			(effects
				(font
					(size 1.27 1.27)
					(thickness 0.15)
				)
			)
		)
		(property "Author" "Antmicro"
			(at 275.750002 352.605 0)
			(layer "B.Fab")
			(hide yes)
			(effects
				(font
					(size 1 1)
					(thickness 0.15)
				)
				(justify mirror)
			)
		)
		(property "Dielectric" "X5R"
			(at 275.750002 352.605 0)
			(layer "B.Fab")
			(hide yes)
			(effects
				(font
					(size 1 1)
					(thickness 0.15)
				)
				(justify mirror)
			)
		)
		(property "License" "Apache-2.0"
			(at 275.750002 352.605 0)
			(layer "B.Fab")
			(hide yes)
			(effects
				(font
					(size 1 1)
					(thickness 0.15)
				)
				(justify mirror)
			)
		)
		(property "MPN" "GRM155R61H104KE14D"
			(at 275.750002 352.605 0)
			(layer "B.Fab")
			(hide yes)
			(effects
				(font
					(size 1 1)
					(thickness 0.15)
				)
				(justify mirror)
			)
		)
		(property "Manufacturer" "Murata"
			(at 275.750002 352.605 0)
			(layer "B.Fab")
			(hide yes)
			(effects
				(font
					(size 1 1)
					(thickness 0.15)
				)
				(justify mirror)
			)
		)
		(property "Val" "100n"
			(at 275.750002 352.605 0)
			(layer "B.Fab")
			(hide yes)
			(effects
				(font
					(size 1 1)
					(thickness 0.15)
				)
				(justify mirror)
			)
		)
		(property "Voltage" "50V"
			(at 275.750002 352.605 0)
			(layer "B.Fab")
			(hide yes)
			(effects
				(font
					(size 1 1)
					(thickness 0.15)
				)
				(justify mirror)
			)
		)
		(sheetname "/FPGA power/")
		(sheetfile "fpga-power.kicad_sch")
		(attr smd)
		(fp_rect
			(start -0.9656 0.4572)
			(end 0.9652 -0.4828)
			(stroke
				(width 0.05)
				(type solid)
			)
			(fill no)
			(layer "B.CrtYd")
		)
		(fp_line
			(start 0.498 0.25)
			(end 0.498 -0.248)
			(stroke
				(width 0.15)
				(type solid)
			)
			(layer "B.Fab")
		)
		(fp_line
			(start 0.498 -0.248)
			(end -0.5 -0.248)
			(stroke
				(width 0.15)
				(type solid)
			)
			(layer "B.Fab")
		)
		(fp_line
			(start -0.5 0.25)
			(end 0.498 0.25)
			(stroke
				(width 0.15)
				(type solid)
			)
			(layer "B.Fab")
		)
		(fp_line
			(start -0.5 -0.248)
			(end -0.5 0.25)
			(stroke
				(width 0.15)
				(type solid)
			)
			(layer "B.Fab")
		)
		(pad "1" smd roundrect
			(at -0.5 0 90)
			(size 0.6 0.6)
			(layers "B.Cu" "B.Mask" "B.Paste")
			(roundrect_rratio 0.25)
			(net 1 "GND")
			(pintype "passive")
		)
		(pad "2" smd roundrect
			(at 0.498 0 180)
			(size 0.6 0.6)
			(layers "B.Cu" "B.Mask" "B.Paste")
			(roundrect_rratio 0.25)
			(net 227 "+1V0")
			(pintype "passive")
		)
	)
	(footprint "antmicro-footprints:C_0402_1005Metric"
		(layer "B.Cu")
		(at 82.75 170.25 90)
		(descr "Capacitor SMD 0402")
		(tags "capacitor SMD 0402")
		(property "Reference" "C129"
			(at 0 0.699 270)
			(layer "B.SilkS")
			(hide yes)
			(effects
				(font
					(size 0.7 0.7)
					(thickness 0.15)
				)
				(justify left bottom mirror)
			)
		)
		(property "Value" "C_1u_0402"
			(at -1.022927 -2.155213 270)
			(layer "B.Fab")
			(effects
				(font
					(size 0.7 0.7)
					(thickness 0.15)
				)
				(justify left bottom mirror)
			)
		)
		(property "Datasheet" "https://product.tdk.com/en/search/capacitor/ceramic/mlcc/info?part_no=C1005X6S1A105K050BC"
			(at 0 0 90)
			(layer "F.Fab")
			(hide yes)
			(effects
				(font
					(size 1.27 1.27)
					(thickness 0.15)
				)
			)
		)
		(property "Author" "Antmicro"
			(at 253 87.5 0)
			(layer "B.Fab")
			(hide yes)
			(effects
				(font
					(size 1 1)
					(thickness 0.15)
				)
				(justify mirror)
			)
		)
		(property "Dielectric" ""
			(at 253 87.5 0)
			(layer "B.Fab")
			(hide yes)
			(effects
				(font
					(size 1 1)
					(thickness 0.15)
				)
				(justify mirror)
			)
		)
		(property "License" "Apache-2.0"
			(at 253 87.5 0)
			(layer "B.Fab")
			(hide yes)
			(effects
				(font
					(size 1 1)
					(thickness 0.15)
				)
				(justify mirror)
			)
		)
		(property "MPN" "C1005X6S1A105K050BC"
			(at 253 87.5 0)
			(layer "B.Fab")
			(hide yes)
			(effects
				(font
					(size 1 1)
					(thickness 0.15)
				)
				(justify mirror)
			)
		)
		(property "Manufacturer" "TDK"
			(at 253 87.5 0)
			(layer "B.Fab")
			(hide yes)
			(effects
				(font
					(size 1 1)
					(thickness 0.15)
				)
				(justify mirror)
			)
		)
		(property "Val" "1u"
			(at 253 87.5 0)
			(layer "B.Fab")
			(hide yes)
			(effects
				(font
					(size 1 1)
					(thickness 0.15)
				)
				(justify mirror)
			)
		)
		(property "Voltage" ""
			(at 253 87.5 0)
			(layer "B.Fab")
			(hide yes)
			(effects
				(font
					(size 1 1)
					(thickness 0.15)
				)
				(justify mirror)
			)
		)
		(sheetname "/HDMI + SD Card/")
		(sheetfile "hdmi-sd-card.kicad_sch")
		(attr smd)
		(fp_rect
			(start -0.9659 0.481258)
			(end 0.9649 -0.458742)
			(stroke
				(width 0.05)
				(type solid)
			)
			(fill no)
			(layer "B.CrtYd")
		)
		(fp_line
			(start 0.499 -0.248)
			(end -0.499 -0.248)
			(stroke
				(width 0.15)
				(type solid)
			)
			(layer "B.Fab")
		)
		(fp_line
			(start -0.499 -0.248)
			(end -0.499 0.25)
			(stroke
				(width 0.15)
				(type solid)
			)
			(layer "B.Fab")
		)
		(fp_line
			(start 0.499 0.25)
			(end 0.499 -0.248)
			(stroke
				(width 0.15)
				(type solid)
			)
			(layer "B.Fab")
		)
		(fp_line
			(start -0.499 0.25)
			(end 0.499 0.25)
			(stroke
				(width 0.15)
				(type solid)
			)
			(layer "B.Fab")
		)
		(pad "1" smd roundrect
			(at -0.484 0 90)
			(size 0.59 0.64)
			(layers "B.Cu" "B.Mask" "B.Paste")
			(roundrect_rratio 0.25)
			(net 200 "+3V3")
			(pintype "passive")
		)
		(pad "2" smd roundrect
			(at 0.484 0 90)
			(size 0.59 0.64)
			(layers "B.Cu" "B.Mask" "B.Paste")
			(roundrect_rratio 0.25)
			(net 1 "GND")
			(pintype "passive")
		)
	)
	(footprint "antmicro-footprints:R_0402_1005Metric"
		(layer "B.Cu")
		(at 184.25 189.47 -90)
		(descr "Resistor SMD 0402")
		(tags "resistor SMD 0402")
		(property "Reference" "R36"
			(at -1.47 -1.4 90)
			(layer "B.SilkS")
			(effects
				(font
					(size 0.7 0.7)
					(thickness 0.15)
				)
				(justify left bottom mirror)
			)
		)
		(property "Value" "R_0R_0402"
			(at -1.011843 -1.772046 90)
			(layer "B.Fab")
			(effects
				(font
					(size 0.7 0.7)
					(thickness 0.15)
				)
				(justify left bottom mirror)
			)
		)
		(property "Datasheet" "https://industrial.panasonic.com/cdbs/www-data/pdf/RDA0000/AOA0000C301.pdf"
			(at 0 0 90)
			(layer "B.Fab")
			(hide yes)
			(effects
				(font
					(size 1.27 1.27)
					(thickness 0.15)
				)
				(justify mirror)
			)
		)
		(property "Manufacturer" "Panasonic"
			(at 0 0 90)
			(unlocked yes)
			(layer "B.Fab")
			(hide yes)
			(effects
				(font
					(size 1 1)
					(thickness 0.15)
				)
				(justify mirror)
			)
		)
		(property "MPN" "ERJ2GE0R00X"
			(at 0 0 90)
			(unlocked yes)
			(layer "B.Fab")
			(hide yes)
			(effects
				(font
					(size 1 1)
					(thickness 0.15)
				)
				(justify mirror)
			)
		)
		(property "Val" "0R"
			(at 0 0 90)
			(unlocked yes)
			(layer "B.Fab")
			(hide yes)
			(effects
				(font
					(size 1 1)
					(thickness 0.15)
				)
				(justify mirror)
			)
		)
		(property "License" "Apache-2.0"
			(at 0 0 90)
			(unlocked yes)
			(layer "B.Fab")
			(hide yes)
			(effects
				(font
					(size 1 1)
					(thickness 0.15)
				)
				(justify mirror)
			)
		)
		(property "Author" "Antmicro"
			(at 0 0 90)
			(unlocked yes)
			(layer "B.Fab")
			(hide yes)
			(effects
				(font
					(size 1 1)
					(thickness 0.15)
				)
				(justify mirror)
			)
		)
		(property "Tolerance" ""
			(at 0 0 90)
			(unlocked yes)
			(layer "B.Fab")
			(hide yes)
			(effects
				(font
					(size 1 1)
					(thickness 0.15)
				)
				(justify mirror)
			)
		)
		(property "Current" "1A"
			(at 0 0 90)
			(unlocked yes)
			(layer "B.Fab")
			(hide yes)
			(effects
				(font
					(size 1 1)
					(thickness 0.15)
				)
				(justify mirror)
			)
		)
		(sheetname "/I^{2}C/")
		(sheetfile "i2c.kicad_sch")
		(attr smd)
		(fp_poly
			(pts
				(xy -0.925 0.47) (xy -0.925 -0.47) (xy 0.925 -0.47) (xy 0.925 0.47)
			)
			(stroke
				(width 0.05)
				(type default)
			)
			(fill no)
			(layer "B.CrtYd")
		)
		(fp_poly
			(pts
				(xy -0.5 0.25) (xy -0.5 -0.25) (xy 0.5 -0.25) (xy 0.5 0.25)
			)
			(stroke
				(width 0.15)
				(type solid)
			)
			(fill no)
			(layer "B.Fab")
		)
		(fp_text user "Author: Antmicro"
			(at -0.95 -4.169 90)
			(layer "B.Fab")
			(effects
				(font
					(size 0.7 0.7)
					(thickness 0.15)
				)
				(justify left bottom mirror)
			)
		)
		(fp_text user "License: Apache-2.0"
			(at -0.949999 -5.169 90)
			(layer "B.Fab")
			(effects
				(font
					(size 0.7 0.7)
					(thickness 0.15)
				)
				(justify left bottom mirror)
			)
		)
		(fp_text user "${REFERENCE}"
			(at -0.95 -3.168 90)
			(layer "B.Fab")
			(effects
				(font
					(size 0.7 0.7)
					(thickness 0.15)
				)
				(justify left bottom mirror)
			)
		)
		(pad "1" smd roundrect
			(at -0.48 0 270)
			(size 0.59 0.64)
			(layers "B.Cu" "B.Mask" "B.Paste")
			(roundrect_rratio 0.25)
			(net 690 "/I^{2}C/PWR.SDA")
			(pintype "passive")
		)
		(pad "2" smd roundrect
			(at 0.48 0 270)
			(size 0.59 0.64)
			(layers "B.Cu" "B.Mask" "B.Paste")
			(roundrect_rratio 0.25)
			(net 761 "Net-(U34-SDA)")
			(pintype "passive")
		)
	)
	(footprint "antmicro-footprints:C_0402_1005Metric"
		(layer "B.Cu")
		(at 139.375001 176.8025 90)
		(descr "Capacitor SMD 0402 (1005 Metric), square (rectangular) end terminal, IPC_7351 nominal, (Body size source: IPC-SM-782 page 76, https://www.pcb-3d.com/wordpress/wp-content/uploads/ipc-sm-782a_amendment_1_and_2.pdf)")
		(tags "capacitor 0402")
		(property "Reference" "C65"
			(at 0 1.17 270)
			(layer "B.SilkS")
			(hide yes)
			(effects
				(font
					(size 0.7 0.7)
					(thickness 0.15)
				)
				(justify left bottom mirror)
			)
		)
		(property "Value" "C_100n_0402"
			(at 0 -1.169 270)
			(layer "B.Fab")
			(effects
				(font
					(size 0.7 0.7)
					(thickness 0.15)
				)
				(justify left bottom mirror)
			)
		)
		(property "Datasheet" "https://www.murata.com/products/productdetail?partno=GRM155R61H104KE14%23"
			(at 0 0 90)
			(layer "F.Fab")
			(hide yes)
			(effects
				(font
					(size 1.27 1.27)
					(thickness 0.15)
				)
			)
		)
		(property "Author" "Antmicro"
			(at 316.177501 37.427499 0)
			(layer "B.Fab")
			(hide yes)
			(effects
				(font
					(size 1 1)
					(thickness 0.15)
				)
				(justify mirror)
			)
		)
		(property "Dielectric" "X5R"
			(at 316.177501 37.427499 0)
			(layer "B.Fab")
			(hide yes)
			(effects
				(font
					(size 1 1)
					(thickness 0.15)
				)
				(justify mirror)
			)
		)
		(property "License" "Apache-2.0"
			(at 316.177501 37.427499 0)
			(layer "B.Fab")
			(hide yes)
			(effects
				(font
					(size 1 1)
					(thickness 0.15)
				)
				(justify mirror)
			)
		)
		(property "MPN" "GRM155R61H104KE14D"
			(at 316.177501 37.427499 0)
			(layer "B.Fab")
			(hide yes)
			(effects
				(font
					(size 1 1)
					(thickness 0.15)
				)
				(justify mirror)
			)
		)
		(property "Manufacturer" "Murata"
			(at 316.177501 37.427499 0)
			(layer "B.Fab")
			(hide yes)
			(effects
				(font
					(size 1 1)
					(thickness 0.15)
				)
				(justify mirror)
			)
		)
		(property "Val" "100n"
			(at 316.177501 37.427499 0)
			(layer "B.Fab")
			(hide yes)
			(effects
				(font
					(size 1 1)
					(thickness 0.15)
				)
				(justify mirror)
			)
		)
		(property "Voltage" "50V"
			(at 316.177501 37.427499 0)
			(layer "B.Fab")
			(hide yes)
			(effects
				(font
					(size 1 1)
					(thickness 0.15)
				)
				(justify mirror)
			)
		)
		(sheetname "/FPGA power/")
		(sheetfile "fpga-power.kicad_sch")
		(attr smd)
		(fp_rect
			(start -0.9656 0.4572)
			(end 0.9652 -0.4828)
			(stroke
				(width 0.05)
				(type solid)
			)
			(fill no)
			(layer "B.CrtYd")
		)
		(fp_line
			(start 0.498 -0.248)
			(end -0.5 -0.248)
			(stroke
				(width 0.15)
				(type solid)
			)
			(layer "B.Fab")
		)
		(fp_line
			(start -0.5 -0.248)
			(end -0.5 0.25)
			(stroke
				(width 0.15)
				(type solid)
			)
			(layer "B.Fab")
		)
		(fp_line
			(start 0.498 0.25)
			(end 0.498 -0.248)
			(stroke
				(width 0.15)
				(type solid)
			)
			(layer "B.Fab")
		)
		(fp_line
			(start -0.5 0.25)
			(end 0.498 0.25)
			(stroke
				(width 0.15)
				(type solid)
			)
			(layer "B.Fab")
		)
		(pad "1" smd roundrect
			(at -0.5 0)
			(size 0.6 0.6)
			(layers "B.Cu" "B.Mask" "B.Paste")
			(roundrect_rratio 0.25)
			(net 1 "GND")
			(pintype "passive")
		)
		(pad "2" smd roundrect
			(at 0.498 0 90)
			(size 0.6 0.6)
			(layers "B.Cu" "B.Mask" "B.Paste")
			(roundrect_rratio 0.25)
			(net 227 "+1V0")
			(pintype "passive")
		)
	)
)
